FILE_TYPE = MULTI_PHYS_TABLE;
PART 'CONN17_H71061002'
{===================================================================================================================================================================================================================}
:PACK_TYPE | MATERIAL | PART_NUMBER     = EnvComp | PART_NUMBER  | JEDEC_TYPE             | DESCRIPTION                                                       | CLASS | COMPONENT_TYPE | HEIGHT     | LEAD_LENGTH   | SPEED_URL | Status |RPL| AML | Bus_Unit | Days;
{===================================================================================================================================================================================================================}
'PIP'      | 'CONN'   | 'H71061-002'(!) = ''      | 'H71061-002' | 'CONN17_H71061002_PIP' | 'CONN_RJ,RJ45,1G3,5,UP,G,GY,UP,EDG,9ST,17,1,MT'                   | 'IO'  | 'THMT'         | '0.447 IN' | '0.071'       | 'http://speed.intel.com:8081/speed/module/pdm/item/pdm_item_detail_direct.asp?item_cde=H71061-002&item_rev=01&url_param=unused' | '' | '' | '' | '' | '' 
'PIP'      | 'EMPTY'  | 'H71061-002'(!) = ''      | 'H71061-002' | 'CONN17_H71061002_PIP' | 'CONN_RJ,RJ45,1G3,5,UP,G,GY,UP,EDG,9ST,17,1,MT'                   | 'IO'  | 'THMT'         | '0.447 IN' | '0.071'       | 'http://speed.intel.com:8081/speed/module/pdm/item/pdm_item_detail_direct.asp?item_cde=H71061-002&item_rev=01&url_param=unused' | '' | '' | '' | '' | '' 
'PIP1'     | 'CONN'   | 'H71061-002'(!) = ''      | 'H71061-002' | 'CONN17_H71061002A_PIP'| 'W/OVAL MTG HOLES, CONN_RJ,RJ45,1G3,5,UP,G,GY,UP,EDG,9ST,17,1,MT' | 'IO'  | 'THMT'         | '0.447 IN' | '0.071'       | 'http://speed.intel.com:8081/speed/module/pdm/item/pdm_item_detail_direct.asp?item_cde=H71061-002&item_rev=01&url_param=unused' | '' | '' | '' | '' | '' 
'PIP1'     | 'EMPTY'  | 'H71061-002'(!) = ''      | 'H71061-002' | 'CONN17_H71061002A_PIP'| 'W/OVAL MTG HOLES, CONN_RJ,RJ45,1G3,5,UP,G,GY,UP,EDG,9ST,17,1,MT' | 'IO'  | 'THMT'         | '0.447 IN' | '0.071'       | 'http://speed.intel.com:8081/speed/module/pdm/item/pdm_item_detail_direct.asp?item_cde=H71061-002&item_rev=01&url_param=unused' | '' | '' | '' | '' | '' 
END_PART
END.
